(kicad_pcb
	(version 20260206)
	(generator "pcbnew")
	(generator_version "10.0")
	(general
		(thickness 1.6)
		(legacy_teardrops no)
	)
	(paper "A4")
	(title_block
		(title "03242023_DA0F0TMBIJ0_F0T_Motherboard_J_brd_V01_OCP.brd")
		(comment 1 "Grand Teton / footprints 303-307 of 6105")
	)
	(layers
		(0 "F.Cu" signal "TOP")
		(4 "In1.Cu" signal "GND")
		(6 "In2.Cu" signal "IN1")
		(8 "In3.Cu" signal "GND1")
		(10 "In4.Cu" signal "IN2")
		(12 "In5.Cu" signal "GND2")
		(14 "In6.Cu" signal "IN3")
		(16 "In7.Cu" signal "GND3")
		(18 "In8.Cu" signal "VCC")
		(20 "In9.Cu" signal "VCC1")
		(22 "In10.Cu" signal "GND4")
		(24 "In11.Cu" signal "IN4")
		(26 "In12.Cu" signal "GND5")
		(28 "In13.Cu" signal "IN5")
		(30 "In14.Cu" signal "GND6")
		(32 "In15.Cu" signal "IN6")
		(34 "In16.Cu" signal "GND7")
		(2 "B.Cu" signal "BOTTOM")
		(9 "F.Adhes" user "F.Adhesive")
		(11 "B.Adhes" user "B.Adhesive")
		(13 "F.Paste" user "Package Geometry/Pastemask Top")
		(15 "B.Paste" user "Package Geometry/Pastemask Bottom")
		(5 "F.SilkS" user "Ref Des/Silkscreen Top")
		(7 "B.SilkS" user "Ref Des/Silkscreen Bottom")
		(1 "F.Mask" user "Board Geometry/Soldermask Top")
		(3 "B.Mask" user "Board Geometry/Soldermask Bottom")
		(17 "Dwgs.User" user "User.Drawings")
		(19 "Cmts.User" user "User.Comments")
		(21 "Eco1.User" user "User.Eco1")
		(23 "Eco2.User" user "User.Eco2")
		(25 "Edge.Cuts" user "Board Geometry/Outline")
		(27 "Margin" user)
		(31 "F.CrtYd" user "Package Geometry/Place Bound Top")
		(29 "B.CrtYd" user "Package Geometry/Place Bound Bottom")
		(35 "F.Fab" user "Ref Des/Assembly Top")
		(33 "B.Fab" user "Ref Des/Assembly Bottom")
	)
	(footprint ""
		(layer "F.Cu")
		(at 312.443622 -39.868348 180)
		(property "Reference" "R1583"
			(at 0 0 180)
			(layer "F.SilkS")
			(hide yes)
			(effects
				(font
					(size 1.27 1.27)
				)
			)
		)
		(property "Value" ""
			(at 0 0 180)
			(layer "F.Fab")
			(effects
				(font
					(size 1.27 1.27)
				)
			)
		)
		(duplicate_pad_numbers_are_jumpers no)
		(fp_line
			(start 0.7874 0.4064)
			(end -0.7874 0.4064)
			(stroke
				(width 0.1524)
				(type default)
			)
			(layer "F.SilkS")
		)
		(fp_line
			(start 0.7874 -0.4064)
			(end 0.7874 0.4064)
			(stroke
				(width 0.1524)
				(type default)
			)
			(layer "F.SilkS")
		)
		(fp_line
			(start -0.7874 0.4064)
			(end -0.7874 -0.4064)
			(stroke
				(width 0.1524)
				(type default)
			)
			(layer "F.SilkS")
		)
		(fp_line
			(start -0.7874 -0.4064)
			(end 0.7874 -0.4064)
			(stroke
				(width 0.1524)
				(type default)
			)
			(layer "F.SilkS")
		)
		(fp_line
			(start 0.67945 0.3048)
			(end 0.120396 0.3048)
			(stroke
				(width 0.1)
				(type default)
			)
			(layer "F.Fab")
		)
		(fp_line
			(start 0.67945 -0.3048)
			(end 0.67945 0.3048)
			(stroke
				(width 0.1)
				(type default)
			)
			(layer "F.Fab")
		)
		(fp_line
			(start 0.12065 -0.2794)
			(end 0.12065 -0.3048)
			(stroke
				(width 0.1)
				(type default)
			)
			(layer "F.Fab")
		)
		(fp_line
			(start 0.12065 -0.3048)
			(end 0.67945 -0.3048)
			(stroke
				(width 0.1)
				(type default)
			)
			(layer "F.Fab")
		)
		(fp_line
			(start 0.120396 0.3048)
			(end 0.120396 0.2794)
			(stroke
				(width 0.1)
				(type default)
			)
			(layer "F.Fab")
		)
		(fp_line
			(start 0.120396 0.2794)
			(end -0.12065 0.2794)
			(stroke
				(width 0.1)
				(type default)
			)
			(layer "F.Fab")
		)
		(fp_line
			(start -0.12065 0.3048)
			(end -0.67945 0.3048)
			(stroke
				(width 0.1)
				(type default)
			)
			(layer "F.Fab")
		)
		(fp_line
			(start -0.12065 0.2794)
			(end -0.12065 0.3048)
			(stroke
				(width 0.1)
				(type default)
			)
			(layer "F.Fab")
		)
		(fp_line
			(start -0.12065 -0.2794)
			(end 0.12065 -0.2794)
			(stroke
				(width 0.1)
				(type default)
			)
			(layer "F.Fab")
		)
		(fp_line
			(start -0.12065 -0.305054)
			(end -0.12065 -0.2794)
			(stroke
				(width 0.1)
				(type default)
			)
			(layer "F.Fab")
		)
		(fp_line
			(start -0.67945 0.3048)
			(end -0.67945 -0.305054)
			(stroke
				(width 0.1)
				(type default)
			)
			(layer "F.Fab")
		)
		(fp_line
			(start -0.67945 -0.305054)
			(end -0.12065 -0.305054)
			(stroke
				(width 0.1)
				(type default)
			)
			(layer "F.Fab")
		)
		(pad "1" smd circle
			(at -0.40005 0 180)
			(size 0 0)
			(layers "F.Cu" "F.Mask" "F.Paste")
			(net "PU_PCH_PLD_3V3AUX_ALERT_N")
		)
		(pad "2" smd circle
			(at 0.40005 0 180)
			(size 0 0)
			(layers "F.Cu" "F.Mask" "F.Paste")
			(net "P3V3_AUX")
		)
	)
	(footprint ""
		(layer "F.Cu")
		(at 79.691738 -147.677632)
		(property "Reference" "U14"
			(at 3.05308 3.23469 0)
			(unlocked yes)
			(layer "F.SilkS")
			(effects
				(font
					(size 0.7874 0.5842)
					(thickness 0.1524)
				)
				(justify left)
			)
		)
		(property "Value" ""
			(at 0 0 0)
			(layer "F.Fab")
			(effects
				(font
					(size 1.27 1.27)
				)
			)
		)
		(duplicate_pad_numbers_are_jumpers no)
		(fp_line
			(start -1.7272 -2.489962)
			(end -0.779018 -2.489962)
			(stroke
				(width 0.1524)
				(type default)
			)
			(layer "F.SilkS")
		)
		(fp_line
			(start -1.7272 2.489962)
			(end -1.7272 -2.489962)
			(stroke
				(width 0.1524)
				(type default)
			)
			(layer "F.SilkS")
		)
		(fp_line
			(start -0.779018 -2.489962)
			(end 0 -1.710944)
			(stroke
				(width 0.1524)
				(type default)
			)
			(layer "F.SilkS")
		)
		(fp_line
			(start 0 -1.710944)
			(end 0.779018 -2.489962)
			(stroke
				(width 0.1524)
				(type default)
			)
			(layer "F.SilkS")
		)
		(fp_line
			(start 0.779018 -2.489962)
			(end 1.7272 -2.489962)
			(stroke
				(width 0.1524)
				(type default)
			)
			(layer "F.SilkS")
		)
		(fp_line
			(start 1.7272 -2.489962)
			(end 1.7272 2.489962)
			(stroke
				(width 0.1524)
				(type default)
			)
			(layer "F.SilkS")
		)
		(fp_line
			(start 1.7272 2.489962)
			(end -1.7272 2.489962)
			(stroke
				(width 0.1524)
				(type default)
			)
			(layer "F.SilkS")
		)
		(fp_poly
			(pts
				(xy -3.821176 -2.2225) (xy -4.837176 -1.7145) (xy -4.837176 -2.7305)
			)
			(stroke
				(width 0)
				(type default)
			)
			(fill yes)
			(layer "F.SilkS")
		)
		(fp_line
			(start -1.994916 -2.489962)
			(end 1.994916 -2.489962)
			(stroke
				(width 0.1)
				(type default)
			)
			(layer "F.Fab")
		)
		(fp_line
			(start -1.994916 2.489962)
			(end -1.994916 -2.489962)
			(stroke
				(width 0.1)
				(type default)
			)
			(layer "F.Fab")
		)
		(fp_line
			(start 1.994916 -2.489962)
			(end 1.994916 2.489962)
			(stroke
				(width 0.1)
				(type default)
			)
			(layer "F.Fab")
		)
		(fp_line
			(start 1.994916 2.489962)
			(end -1.994916 2.489962)
			(stroke
				(width 0.1)
				(type default)
			)
			(layer "F.Fab")
		)
		(fp_poly
			(pts
				(xy -4.837176 -2.7305) (xy -4.837176 -1.7145) (xy -3.821176 -2.2225)
			)
			(stroke
				(width 0)
				(type default)
			)
			(fill yes)
			(layer "F.Fab")
		)
		(pad "1" smd rect
			(at -2.6924 -2.2225 270)
			(size 0.4318 1.6764)
			(layers "F.Cu" "F.Mask" "F.Paste")
			(net "FM_SPD_REMOTE_EN")
		)
		(pad "2" smd rect
			(at -2.6924 -1.5875 270)
			(size 0.4318 1.6764)
			(layers "F.Cu" "F.Mask" "F.Paste")
			(net "I3C_SPD_DDRABCD_CPU1_R_SCL")
		)
		(pad "3" smd rect
			(at -2.6924 -0.9525 270)
			(size 0.4318 1.6764)
			(layers "F.Cu" "F.Mask" "F.Paste")
			(net "I3C_SPD_DDRABCD_CPU1_BMC_SCL")
		)
		(pad "4" smd rect
			(at -2.6924 -0.3175 270)
			(size 0.4318 1.6764)
			(layers "F.Cu" "F.Mask" "F.Paste")
			(net "I3C_SPD_DDRABCD_CPU1_LVC1_R_SCL")
		)
		(pad "5" smd rect
			(at -2.6924 0.3175 270)
			(size 0.4318 1.6764)
			(layers "F.Cu" "F.Mask" "F.Paste")
			(net "I3C_SPD_DDRABCD_CPU1_R_SDA")
		)
		(pad "6" smd rect
			(at -2.6924 0.9525 270)
			(size 0.4318 1.6764)
			(layers "F.Cu" "F.Mask" "F.Paste")
			(net "I3C_SPD_DDRABCD_CPU1_BMC_SDA")
		)
		(pad "7" smd rect
			(at -2.6924 1.5875 270)
			(size 0.4318 1.6764)
			(layers "F.Cu" "F.Mask" "F.Paste")
			(net "I3C_SPD_DDRABCD_CPU1_LVC1_R_SDA")
		)
		(pad "8" smd rect
			(at -2.6924 2.2225 270)
			(size 0.4318 1.6764)
			(layers "F.Cu" "F.Mask" "F.Paste")
			(net "GND")
		)
		(pad "9" smd rect
			(at 2.6924 2.2225 270)
			(size 0.4318 1.6764)
			(layers "F.Cu" "F.Mask" "F.Paste")
			(net "I3C_SPD_DDREFGH_CPU1_LVC1_R_SCL")
		)
		(pad "10" smd rect
			(at 2.6924 1.5875 270)
			(size 0.4318 1.6764)
			(layers "F.Cu" "F.Mask" "F.Paste")
			(net "I3C_SPD_DDREFGH_CPU1_BMC_SCL")
		)
		(pad "11" smd rect
			(at 2.6924 0.9525 270)
			(size 0.4318 1.6764)
			(layers "F.Cu" "F.Mask" "F.Paste")
			(net "I3C_SPD_DDREFGH_CPU1_R_SCL")
		)
		(pad "12" smd rect
			(at 2.6924 0.3175 270)
			(size 0.4318 1.6764)
			(layers "F.Cu" "F.Mask" "F.Paste")
			(net "I3C_SPD_DDREFGH_CPU1_LVC1_R_SDA")
		)
		(pad "13" smd rect
			(at 2.6924 -0.3175 270)
			(size 0.4318 1.6764)
			(layers "F.Cu" "F.Mask" "F.Paste")
			(net "I3C_SPD_DDREFGH_CPU1_BMC_SDA")
		)
		(pad "14" smd rect
			(at 2.6924 -0.9525 270)
			(size 0.4318 1.6764)
			(layers "F.Cu" "F.Mask" "F.Paste")
			(net "I3C_SPD_DDREFGH_CPU1_R_SDA")
		)
		(pad "15" smd rect
			(at 2.6924 -1.5875 270)
			(size 0.4318 1.6764)
			(layers "F.Cu" "F.Mask" "F.Paste")
			(net "PD_I3C_SPD_DDR_CPU1_OE_N")
		)
		(pad "16" smd rect
			(at 2.6924 -2.2225 270)
			(size 0.4318 1.6764)
			(layers "F.Cu" "F.Mask" "F.Paste")
			(net "P3V3_AUX")
		)
	)
	(footprint ""
		(layer "F.Cu")
		(at 351.6757 -65.354962)
		(property "Reference" "C144"
			(at 0 0 0)
			(layer "F.SilkS")
			(hide yes)
			(effects
				(font
					(size 1.27 1.27)
				)
			)
		)
		(property "Value" ""
			(at 0 0 0)
			(layer "F.Fab")
			(effects
				(font
					(size 1.27 1.27)
				)
			)
		)
		(duplicate_pad_numbers_are_jumpers no)
		(fp_line
			(start -0.299974 -0.150114)
			(end 0.299974 -0.150114)
			(stroke
				(width 0.1)
				(type default)
			)
			(layer "F.Fab")
		)
		(fp_line
			(start -0.299974 0.150114)
			(end -0.299974 -0.150114)
			(stroke
				(width 0.1)
				(type default)
			)
			(layer "F.Fab")
		)
		(fp_line
			(start 0.299974 -0.150114)
			(end 0.299974 0.150114)
			(stroke
				(width 0.1)
				(type default)
			)
			(layer "F.Fab")
		)
		(fp_line
			(start 0.299974 0.150114)
			(end -0.299974 0.150114)
			(stroke
				(width 0.1)
				(type default)
			)
			(layer "F.Fab")
		)
		(pad "1" smd rect
			(at -0.2667 0)
			(size 0.3048 0.381)
			(layers "F.Cu" "F.Mask" "F.Paste")
			(net "DMI_CPU0_PCH_TX_C_DP<5>")
		)
		(pad "2" smd rect
			(at 0.2667 0)
			(size 0.3048 0.381)
			(layers "F.Cu" "F.Mask" "F.Paste")
			(net "DMI_CPU0_PCH_TX_DP<5>")
		)
		(zone
			(layer "In1.Cu")
			(hatch none 0.5)
			(connect_pads
				(clearance 0)
			)
			(min_thickness 0.25)
			(keepout
				(tracks not_allowed)
				(vias allowed)
				(pads allowed)
				(copperpour not_allowed)
				(footprints allowed)
			)
			(placement
				(enabled no)
				(sheetname "")
			)
			(fill
				(thermal_gap 0.5)
				(thermal_bridge_width 0.5)
				(island_removal_mode 0)
			)
			(polygon
				(pts
					(arc
						(start 351.282 -65.113662)
						(mid 351.228118 -65.13598)
						(end 351.2058 -65.189862)
					)
					(arc
						(start 351.2058 -65.520062)
						(mid 351.228118 -65.573944)
						(end 351.282 -65.596262)
					)
					(arc
						(start 351.536 -65.596262)
						(mid 351.589882 -65.573944)
						(end 351.6122 -65.520062)
					)
					(arc
						(start 351.6122 -65.189862)
						(mid 351.589882 -65.13598)
						(end 351.536 -65.113662)
					)
				)
			)
		)
		(zone
			(layer "In1.Cu")
			(hatch none 0.5)
			(connect_pads
				(clearance 0)
			)
			(min_thickness 0.25)
			(keepout
				(tracks not_allowed)
				(vias allowed)
				(pads allowed)
				(copperpour not_allowed)
				(footprints allowed)
			)
			(placement
				(enabled no)
				(sheetname "")
			)
			(fill
				(thermal_gap 0.5)
				(thermal_bridge_width 0.5)
				(island_removal_mode 0)
			)
			(polygon
				(pts
					(arc
						(start 351.8154 -65.113662)
						(mid 351.761518 -65.13598)
						(end 351.7392 -65.189862)
					)
					(arc
						(start 351.7392 -65.520062)
						(mid 351.761518 -65.573944)
						(end 351.8154 -65.596262)
					)
					(arc
						(start 352.0694 -65.596262)
						(mid 352.123282 -65.573944)
						(end 352.1456 -65.520062)
					)
					(arc
						(start 352.1456 -65.189862)
						(mid 352.123282 -65.13598)
						(end 352.0694 -65.113662)
					)
				)
			)
		)
	)
	(footprint ""
		(layer "F.Cu")
		(at 249.916696 -43.556682 180)
		(property "Reference" "PR3961"
			(at 0 0 180)
			(layer "F.SilkS")
			(hide yes)
			(effects
				(font
					(size 1.27 1.27)
				)
			)
		)
		(property "Value" ""
			(at 0 0 180)
			(layer "F.Fab")
			(effects
				(font
					(size 1.27 1.27)
				)
			)
		)
		(duplicate_pad_numbers_are_jumpers no)
		(fp_line
			(start 0.7874 0.4064)
			(end -0.7874 0.4064)
			(stroke
				(width 0.1524)
				(type default)
			)
			(layer "F.SilkS")
		)
		(fp_line
			(start 0.7874 -0.4064)
			(end 0.7874 0.4064)
			(stroke
				(width 0.1524)
				(type default)
			)
			(layer "F.SilkS")
		)
		(fp_line
			(start -0.7874 0.4064)
			(end -0.7874 -0.4064)
			(stroke
				(width 0.1524)
				(type default)
			)
			(layer "F.SilkS")
		)
		(fp_line
			(start -0.7874 -0.4064)
			(end 0.7874 -0.4064)
			(stroke
				(width 0.1524)
				(type default)
			)
			(layer "F.SilkS")
		)
		(fp_line
			(start 0.67945 0.3048)
			(end 0.120396 0.3048)
			(stroke
				(width 0.1)
				(type default)
			)
			(layer "F.Fab")
		)
		(fp_line
			(start 0.67945 -0.3048)
			(end 0.67945 0.3048)
			(stroke
				(width 0.1)
				(type default)
			)
			(layer "F.Fab")
		)
		(fp_line
			(start 0.12065 -0.2794)
			(end 0.12065 -0.3048)
			(stroke
				(width 0.1)
				(type default)
			)
			(layer "F.Fab")
		)
		(fp_line
			(start 0.12065 -0.3048)
			(end 0.67945 -0.3048)
			(stroke
				(width 0.1)
				(type default)
			)
			(layer "F.Fab")
		)
		(fp_line
			(start 0.120396 0.3048)
			(end 0.120396 0.2794)
			(stroke
				(width 0.1)
				(type default)
			)
			(layer "F.Fab")
		)
		(fp_line
			(start 0.120396 0.2794)
			(end -0.12065 0.2794)
			(stroke
				(width 0.1)
				(type default)
			)
			(layer "F.Fab")
		)
		(fp_line
			(start -0.12065 0.3048)
			(end -0.67945 0.3048)
			(stroke
				(width 0.1)
				(type default)
			)
			(layer "F.Fab")
		)
		(fp_line
			(start -0.12065 0.2794)
			(end -0.12065 0.3048)
			(stroke
				(width 0.1)
				(type default)
			)
			(layer "F.Fab")
		)
		(fp_line
			(start -0.12065 -0.2794)
			(end 0.12065 -0.2794)
			(stroke
				(width 0.1)
				(type default)
			)
			(layer "F.Fab")
		)
		(fp_line
			(start -0.12065 -0.305054)
			(end -0.12065 -0.2794)
			(stroke
				(width 0.1)
				(type default)
			)
			(layer "F.Fab")
		)
		(fp_line
			(start -0.67945 0.3048)
			(end -0.67945 -0.305054)
			(stroke
				(width 0.1)
				(type default)
			)
			(layer "F.Fab")
		)
		(fp_line
			(start -0.67945 -0.305054)
			(end -0.12065 -0.305054)
			(stroke
				(width 0.1)
				(type default)
			)
			(layer "F.Fab")
		)
		(pad "1" smd circle
			(at -0.40005 0 180)
			(size 0 0)
			(layers "F.Cu" "F.Mask" "F.Paste")
			(net "P12V_E1S_UV_0")
		)
		(pad "2" smd circle
			(at 0.40005 0 180)
			(size 0 0)
			(layers "F.Cu" "F.Mask" "F.Paste")
			(net "P12V_E1S_OV_0")
		)
	)
	(footprint ""
		(layer "F.Cu")
		(at 317.396622 -53.787548)
		(property "Reference" "R371"
			(at 0 0 0)
			(layer "F.SilkS")
			(hide yes)
			(effects
				(font
					(size 1.27 1.27)
				)
			)
		)
		(property "Value" ""
			(at 0 0 0)
			(layer "F.Fab")
			(effects
				(font
					(size 1.27 1.27)
				)
			)
		)
		(duplicate_pad_numbers_are_jumpers no)
		(fp_line
			(start -0.7874 -0.4064)
			(end 0.7874 -0.4064)
			(stroke
				(width 0.1524)
				(type default)
			)
			(layer "F.SilkS")
		)
		(fp_line
			(start -0.7874 0.4064)
			(end -0.7874 -0.4064)
			(stroke
				(width 0.1524)
				(type default)
			)
			(layer "F.SilkS")
		)
		(fp_line
			(start 0.7874 -0.4064)
			(end 0.7874 0.4064)
			(stroke
				(width 0.1524)
				(type default)
			)
			(layer "F.SilkS")
		)
		(fp_line
			(start 0.7874 0.4064)
			(end -0.7874 0.4064)
			(stroke
				(width 0.1524)
				(type default)
			)
			(layer "F.SilkS")
		)
		(fp_line
			(start -0.67945 -0.305054)
			(end -0.12065 -0.305054)
			(stroke
				(width 0.1)
				(type default)
			)
			(layer "F.Fab")
		)
		(fp_line
			(start -0.67945 0.3048)
			(end -0.67945 -0.305054)
			(stroke
				(width 0.1)
				(type default)
			)
			(layer "F.Fab")
		)
		(fp_line
			(start -0.12065 -0.305054)
			(end -0.12065 -0.2794)
			(stroke
				(width 0.1)
				(type default)
			)
			(layer "F.Fab")
		)
		(fp_line
			(start -0.12065 -0.2794)
			(end 0.12065 -0.2794)
			(stroke
				(width 0.1)
				(type default)
			)
			(layer "F.Fab")
		)
		(fp_line
			(start -0.12065 0.2794)
			(end -0.12065 0.3048)
			(stroke
				(width 0.1)
				(type default)
			)
			(layer "F.Fab")
		)
		(fp_line
			(start -0.12065 0.3048)
			(end -0.67945 0.3048)
			(stroke
				(width 0.1)
				(type default)
			)
			(layer "F.Fab")
		)
		(fp_line
			(start 0.120396 0.2794)
			(end -0.12065 0.2794)
			(stroke
				(width 0.1)
				(type default)
			)
			(layer "F.Fab")
		)
		(fp_line
			(start 0.120396 0.3048)
			(end 0.120396 0.2794)
			(stroke
				(width 0.1)
				(type default)
			)
			(layer "F.Fab")
		)
		(fp_line
			(start 0.12065 -0.3048)
			(end 0.67945 -0.3048)
			(stroke
				(width 0.1)
				(type default)
			)
			(layer "F.Fab")
		)
		(fp_line
			(start 0.12065 -0.2794)
			(end 0.12065 -0.3048)
			(stroke
				(width 0.1)
				(type default)
			)
			(layer "F.Fab")
		)
		(fp_line
			(start 0.67945 -0.3048)
			(end 0.67945 0.3048)
			(stroke
				(width 0.1)
				(type default)
			)
			(layer "F.Fab")
		)
		(fp_line
			(start 0.67945 0.3048)
			(end 0.120396 0.3048)
			(stroke
				(width 0.1)
				(type default)
			)
			(layer "F.Fab")
		)
		(pad "1" smd circle
			(at -0.40005 0)
			(size 0 0)
			(layers "F.Cu" "F.Mask" "F.Paste")
			(net "P3V3_AUX")
		)
		(pad "2" smd circle
			(at 0.40005 0)
			(size 0 0)
			(layers "F.Cu" "F.Mask" "F.Paste")
			(net "FM_PCH_BOOT_BIOS_STRAP")
		)
	)
)
